(kicad_pcb
	(version 20241229)
	(generator "pcbnew")
	(generator_version "9.0")
	(general
		(thickness 1.258)
		(legacy_teardrops no)
	)
	(paper "A4")
	(title_block
		(date "2024-05-27")
		(rev "1.1.2")
		(comment 9 "footprints 29-35 of 64")
	)
	(layers
		(0 "F.Cu" signal)
		(4 "In1.Cu" power)
		(6 "In2.Cu" power)
		(8 "In3.Cu" signal)
		(10 "In4.Cu" signal)
		(2 "B.Cu" signal)
		(9 "F.Adhes" user "F.Adhesive")
		(11 "B.Adhes" user "B.Adhesive")
		(13 "F.Paste" user)
		(15 "B.Paste" user)
		(5 "F.SilkS" user "F.Silkscreen")
		(7 "B.SilkS" user "B.Silkscreen")
		(1 "F.Mask" user)
		(3 "B.Mask" user)
		(17 "Dwgs.User" user "User.Drawings")
		(19 "Cmts.User" user "User.Comments")
		(21 "Eco1.User" user "User.Eco1")
		(23 "Eco2.User" user "User.Eco2")
		(25 "Edge.Cuts" user)
		(27 "Margin" user)
		(31 "F.CrtYd" user "F.Courtyard")
		(29 "B.CrtYd" user "B.Courtyard")
		(35 "F.Fab" user)
		(33 "B.Fab" user)
	)
	(footprint "antmicro-footprints:R_0402_1005Metric"
		(layer "F.Cu")
		(at 150.225 91.15 -90)
		(descr "Resistor SMD 0402")
		(tags "resistor SMD 0402")
		(property "Reference" "R5"
			(at 3.05 -0.385 270)
			(layer "F.SilkS")
			(effects
				(font
					(size 0.7 0.7)
					(thickness 0.15)
				)
				(justify left bottom)
			)
		)
		(property "Value" "R_1k_0402"
			(at 0 1.4 270)
			(layer "F.Fab")
			(hide yes)
			(effects
				(font
					(size 0.7 0.7)
					(thickness 0.15)
				)
				(justify left bottom)
			)
		)
		(property "Description" "1k resistor in 0402 package with 1% tolerance"
			(at 0 0 270)
			(layer "F.Fab")
			(hide yes)
			(effects
				(font
					(size 1.27 1.27)
					(thickness 0.15)
				)
			)
		)
		(property "Author" "Antmicro"
			(at 59.075 241.375 0)
			(layer "F.Fab")
			(hide yes)
			(effects
				(font
					(size 1 1)
					(thickness 0.15)
				)
			)
		)
		(property "License" "Apache-2.0"
			(at 59.075 241.375 0)
			(layer "F.Fab")
			(hide yes)
			(effects
				(font
					(size 1 1)
					(thickness 0.15)
				)
			)
		)
		(property "MPN" "CR0402-FX-1001GLF"
			(at 59.075 241.375 0)
			(layer "F.Fab")
			(hide yes)
			(effects
				(font
					(size 1 1)
					(thickness 0.15)
				)
			)
		)
		(property "Manufacturer" "Bourns"
			(at 59.075 241.375 0)
			(layer "F.Fab")
			(hide yes)
			(effects
				(font
					(size 1 1)
					(thickness 0.15)
				)
			)
		)
		(property "Tolerance" "1%"
			(at 59.075 241.375 0)
			(layer "F.Fab")
			(hide yes)
			(effects
				(font
					(size 1 1)
					(thickness 0.15)
				)
			)
		)
		(property "Val" "1k"
			(at 59.075 241.375 0)
			(layer "F.Fab")
			(hide yes)
			(effects
				(font
					(size 1 1)
					(thickness 0.15)
				)
			)
		)
		(sheetname "DDR5")
		(sheetfile "ddr5.kicad_sch")
		(attr smd)
		(fp_rect
			(start -0.925 -0.47)
			(end 0.925 0.47)
			(stroke
				(width 0.05)
				(type default)
			)
			(fill no)
			(layer "F.CrtYd")
		)
		(fp_rect
			(start -0.5 -0.25)
			(end 0.5 0.25)
			(stroke
				(width 0.15)
				(type solid)
			)
			(fill no)
			(layer "F.Fab")
		)
		(pad "1" smd roundrect
			(at -0.48 0 270)
			(size 0.59 0.64)
			(layers "F.Cu" "F.Mask" "F.Paste")
			(roundrect_rratio 0.25)
			(net 2 "VDDQ")
			(pintype "passive")
		)
		(pad "2" smd roundrect
			(at 0.48 0 270)
			(size 0.59 0.64)
			(layers "F.Cu" "F.Mask" "F.Paste")
			(roundrect_rratio 0.25)
			(net 60 "/DDR5/R_RESET_N")
			(pintype "passive")
		)
	)
	(footprint "antmicro-footprints:R_0402_1005Metric"
		(layer "F.Cu")
		(at 157.525 87.25 -90)
		(descr "Resistor SMD 0402")
		(tags "resistor SMD 0402")
		(property "Reference" "R6"
			(at 0.82 -1.325 270)
			(layer "F.SilkS")
			(effects
				(font
					(size 0.7 0.7)
					(thickness 0.15)
				)
				(justify left bottom)
			)
		)
		(property "Value" "R_240R_0402"
			(at 0 1.4 270)
			(layer "F.Fab")
			(hide yes)
			(effects
				(font
					(size 0.7 0.7)
					(thickness 0.15)
				)
				(justify left bottom)
			)
		)
		(property "Description" "240R resistor in 0402 package with 1% tolerance"
			(at 0 0 270)
			(layer "F.Fab")
			(hide yes)
			(effects
				(font
					(size 1.27 1.27)
					(thickness 0.15)
				)
			)
		)
		(property "Author" "Antmicro"
			(at 70.275 244.775 0)
			(layer "F.Fab")
			(hide yes)
			(effects
				(font
					(size 1 1)
					(thickness 0.15)
				)
			)
		)
		(property "License" "Apache-2.0"
			(at 70.275 244.775 0)
			(layer "F.Fab")
			(hide yes)
			(effects
				(font
					(size 1 1)
					(thickness 0.15)
				)
			)
		)
		(property "MPN" "CR0402-FX-2400GLF"
			(at 70.275 244.775 0)
			(layer "F.Fab")
			(hide yes)
			(effects
				(font
					(size 1 1)
					(thickness 0.15)
				)
			)
		)
		(property "Manufacturer" "Bourns"
			(at 70.275 244.775 0)
			(layer "F.Fab")
			(hide yes)
			(effects
				(font
					(size 1 1)
					(thickness 0.15)
				)
			)
		)
		(property "Tolerance" "1%"
			(at 70.275 244.775 0)
			(layer "F.Fab")
			(hide yes)
			(effects
				(font
					(size 1 1)
					(thickness 0.15)
				)
			)
		)
		(property "Val" "240R"
			(at 70.275 244.775 0)
			(layer "F.Fab")
			(hide yes)
			(effects
				(font
					(size 1 1)
					(thickness 0.15)
				)
			)
		)
		(sheetname "DDR5")
		(sheetfile "ddr5.kicad_sch")
		(attr smd)
		(fp_rect
			(start -0.925 -0.47)
			(end 0.925 0.47)
			(stroke
				(width 0.05)
				(type default)
			)
			(fill no)
			(layer "F.CrtYd")
		)
		(fp_rect
			(start -0.5 -0.25)
			(end 0.5 0.25)
			(stroke
				(width 0.15)
				(type solid)
			)
			(fill no)
			(layer "F.Fab")
		)
		(pad "1" smd roundrect
			(at -0.48 0 270)
			(size 0.59 0.64)
			(layers "F.Cu" "F.Mask" "F.Paste")
			(roundrect_rratio 0.25)
			(net 61 "/DDR5/ZQ")
			(pintype "passive")
		)
		(pad "2" smd roundrect
			(at 0.48 0 270)
			(size 0.59 0.64)
			(layers "F.Cu" "F.Mask" "F.Paste")
			(roundrect_rratio 0.25)
			(net 1 "GND")
			(pintype "passive")
		)
	)
	(footprint "antmicro-footprints:R_0402_1005Metric"
		(layer "F.Cu")
		(at 149.225 91.15 -90)
		(descr "Resistor SMD 0402")
		(tags "resistor SMD 0402")
		(property "Reference" "R7"
			(at 3.05 -0.385 270)
			(layer "F.SilkS")
			(effects
				(font
					(size 0.7 0.7)
					(thickness 0.15)
				)
				(justify left bottom)
			)
		)
		(property "Value" "R_0R_0402"
			(at 0 1.4 270)
			(layer "F.Fab")
			(hide yes)
			(effects
				(font
					(size 0.7 0.7)
					(thickness 0.15)
				)
				(justify left bottom)
			)
		)
		(property "Description" "0R resistor in 0402 package with unspecified tolerance"
			(at 0 0 270)
			(layer "F.Fab")
			(hide yes)
			(effects
				(font
					(size 1.27 1.27)
					(thickness 0.15)
				)
			)
		)
		(property "Author" "Antmicro"
			(at 58.075 240.375 0)
			(layer "F.Fab")
			(hide yes)
			(effects
				(font
					(size 1 1)
					(thickness 0.15)
				)
			)
		)
		(property "Current" "1A"
			(at 58.075 240.375 0)
			(layer "F.Fab")
			(hide yes)
			(effects
				(font
					(size 1 1)
					(thickness 0.15)
				)
			)
		)
		(property "License" "Apache-2.0"
			(at 58.075 240.375 0)
			(layer "F.Fab")
			(hide yes)
			(effects
				(font
					(size 1 1)
					(thickness 0.15)
				)
			)
		)
		(property "MPN" "ERJ2GE0R00X"
			(at 58.075 240.375 0)
			(layer "F.Fab")
			(hide yes)
			(effects
				(font
					(size 1 1)
					(thickness 0.15)
				)
			)
		)
		(property "Manufacturer" "Panasonic"
			(at 58.075 240.375 0)
			(layer "F.Fab")
			(hide yes)
			(effects
				(font
					(size 1 1)
					(thickness 0.15)
				)
			)
		)
		(property "Tolerance" ""
			(at 58.075 240.375 0)
			(layer "F.Fab")
			(hide yes)
			(effects
				(font
					(size 1 1)
					(thickness 0.15)
				)
			)
		)
		(property "Val" "0R"
			(at 58.075 240.375 0)
			(layer "F.Fab")
			(hide yes)
			(effects
				(font
					(size 1 1)
					(thickness 0.15)
				)
			)
		)
		(sheetname "DDR5")
		(sheetfile "ddr5.kicad_sch")
		(attr smd)
		(fp_rect
			(start -0.925 -0.47)
			(end 0.925 0.47)
			(stroke
				(width 0.05)
				(type default)
			)
			(fill no)
			(layer "F.CrtYd")
		)
		(fp_rect
			(start -0.5 -0.25)
			(end 0.5 0.25)
			(stroke
				(width 0.15)
				(type solid)
			)
			(fill no)
			(layer "F.Fab")
		)
		(pad "1" smd roundrect
			(at -0.48 0 270)
			(size 0.59 0.64)
			(layers "F.Cu" "F.Mask" "F.Paste")
			(roundrect_rratio 0.25)
			(net 60 "/DDR5/R_RESET_N")
			(pintype "passive")
		)
		(pad "2" smd roundrect
			(at 0.48 0 270)
			(size 0.59 0.64)
			(layers "F.Cu" "F.Mask" "F.Paste")
			(roundrect_rratio 0.25)
			(net 3 "RESET_N")
			(pintype "passive")
		)
	)
	(footprint "antmicro-footprints:R_0402_1005Metric"
		(layer "F.Cu")
		(at 157.525 89.185 -90)
		(descr "Resistor SMD 0402")
		(tags "resistor SMD 0402")
		(property "Reference" "R19"
			(at 1.115 -1.335 270)
			(layer "F.SilkS")
			(effects
				(font
					(size 0.7 0.7)
					(thickness 0.15)
				)
				(justify left bottom)
			)
		)
		(property "Value" "R_0R_0402"
			(at 0 1.4 270)
			(layer "F.Fab")
			(hide yes)
			(effects
				(font
					(size 0.7 0.7)
					(thickness 0.15)
				)
				(justify left bottom)
			)
		)
		(property "Description" "0R resistor in 0402 package with unspecified tolerance"
			(at 0 0 270)
			(layer "F.Fab")
			(hide yes)
			(effects
				(font
					(size 1.27 1.27)
					(thickness 0.15)
				)
			)
		)
		(property "Author" "Antmicro"
			(at 68.34 246.71 0)
			(layer "F.Fab")
			(hide yes)
			(effects
				(font
					(size 1 1)
					(thickness 0.15)
				)
			)
		)
		(property "Current" "1A"
			(at 68.34 246.71 0)
			(layer "F.Fab")
			(hide yes)
			(effects
				(font
					(size 1 1)
					(thickness 0.15)
				)
			)
		)
		(property "License" "Apache-2.0"
			(at 68.34 246.71 0)
			(layer "F.Fab")
			(hide yes)
			(effects
				(font
					(size 1 1)
					(thickness 0.15)
				)
			)
		)
		(property "MPN" "ERJ2GE0R00X"
			(at 68.34 246.71 0)
			(layer "F.Fab")
			(hide yes)
			(effects
				(font
					(size 1 1)
					(thickness 0.15)
				)
			)
		)
		(property "Manufacturer" "Panasonic"
			(at 68.34 246.71 0)
			(layer "F.Fab")
			(hide yes)
			(effects
				(font
					(size 1 1)
					(thickness 0.15)
				)
			)
		)
		(property "Tolerance" ""
			(at 68.34 246.71 0)
			(layer "F.Fab")
			(hide yes)
			(effects
				(font
					(size 1 1)
					(thickness 0.15)
				)
			)
		)
		(property "Val" "0R"
			(at 68.34 246.71 0)
			(layer "F.Fab")
			(hide yes)
			(effects
				(font
					(size 1 1)
					(thickness 0.15)
				)
			)
		)
		(sheetname "DDR5")
		(sheetfile "ddr5.kicad_sch")
		(attr smd)
		(fp_rect
			(start -0.925 -0.47)
			(end 0.925 0.47)
			(stroke
				(width 0.05)
				(type default)
			)
			(fill no)
			(layer "F.CrtYd")
		)
		(fp_rect
			(start -0.5 -0.25)
			(end 0.5 0.25)
			(stroke
				(width 0.15)
				(type solid)
			)
			(fill no)
			(layer "F.Fab")
		)
		(pad "1" smd roundrect
			(at -0.48 0 270)
			(size 0.59 0.64)
			(layers "F.Cu" "F.Mask" "F.Paste")
			(roundrect_rratio 0.25)
			(net 66 "/DDR5/R_LBDQS")
			(pintype "passive")
		)
		(pad "2" smd roundrect
			(at 0.48 0 270)
			(size 0.59 0.64)
			(layers "F.Cu" "F.Mask" "F.Paste")
			(roundrect_rratio 0.25)
			(net 36 "LBDQS")
			(pintype "passive")
		)
	)
	(footprint "antmicro-footprints:C_0201"
		(layer "F.Cu")
		(at 145 87.2 -90)
		(descr "Capacitor SMD 0201")
		(tags "capacitor SMD 0201")
		(property "Reference" "C24"
			(at 2.87 -0.24 90)
			(layer "F.SilkS")
			(effects
				(font
					(size 0.7 0.7)
					(thickness 0.15)
				)
				(justify right bottom)
			)
		)
		(property "Value" "C_100n_0201"
			(at 0 1.4 90)
			(layer "F.Fab")
			(hide yes)
			(effects
				(font
					(size 0.7 0.7)
					(thickness 0.15)
				)
				(justify right bottom)
			)
		)
		(property "Description" "SMD Multilayer Ceramic Capacitor, 0.1 µF, 6.3 V, 0201 [0603 Metric], ± 10%, X6S, CC Series"
			(at 0 0 270)
			(layer "F.Fab")
			(hide yes)
			(effects
				(font
					(size 1.27 1.27)
					(thickness 0.15)
				)
			)
		)
		(property "Author" "Antmicro"
			(at 57.8 232.2 0)
			(layer "F.Fab")
			(hide yes)
			(effects
				(font
					(size 1 1)
					(thickness 0.15)
				)
			)
		)
		(property "Dielectric" ""
			(at 57.8 232.2 0)
			(layer "F.Fab")
			(hide yes)
			(effects
				(font
					(size 1 1)
					(thickness 0.15)
				)
			)
		)
		(property "License" "Apache-2.0"
			(at 57.8 232.2 0)
			(layer "F.Fab")
			(hide yes)
			(effects
				(font
					(size 1 1)
					(thickness 0.15)
				)
			)
		)
		(property "MPN" "CC0201KRX6S5BB104"
			(at 57.8 232.2 0)
			(layer "F.Fab")
			(hide yes)
			(effects
				(font
					(size 1 1)
					(thickness 0.15)
				)
			)
		)
		(property "Manufacturer" "YAGEO"
			(at 57.8 232.2 0)
			(layer "F.Fab")
			(hide yes)
			(effects
				(font
					(size 1 1)
					(thickness 0.15)
				)
			)
		)
		(property "Public" "False"
			(at 57.8 232.2 0)
			(layer "F.Fab")
			(hide yes)
			(effects
				(font
					(size 1 1)
					(thickness 0.15)
				)
			)
		)
		(property "Val" "100n"
			(at 57.8 232.2 0)
			(layer "F.Fab")
			(hide yes)
			(effects
				(font
					(size 1 1)
					(thickness 0.15)
				)
			)
		)
		(property "Voltage" ""
			(at 57.8 232.2 0)
			(layer "F.Fab")
			(hide yes)
			(effects
				(font
					(size 1 1)
					(thickness 0.15)
				)
			)
		)
		(sheetname "DDR5")
		(sheetfile "ddr5.kicad_sch")
		(attr smd)
		(fp_rect
			(start -0.7 -0.35)
			(end 0.7 0.35)
			(stroke
				(width 0.05)
				(type default)
			)
			(fill no)
			(layer "F.CrtYd")
		)
		(fp_rect
			(start 0.3 0.15)
			(end -0.301 -0.149)
			(stroke
				(width 0.15)
				(type solid)
			)
			(fill no)
			(layer "F.Fab")
		)
		(pad "" smd roundrect
			(at -0.349 -0.002 270)
			(size 0.318 0.36)
			(layers "F.Paste")
			(roundrect_rratio 0.25)
		)
		(pad "" smd roundrect
			(at 0.341 -0.002 270)
			(size 0.318 0.36)
			(layers "F.Paste")
			(roundrect_rratio 0.25)
		)
		(pad "1" smd roundrect
			(at -0.321 -0.002 270)
			(size 0.46 0.4)
			(layers "F.Cu" "F.Mask")
			(roundrect_rratio 0.25)
			(net 19 "VPP")
			(pintype "passive")
		)
		(pad "2" smd roundrect
			(at 0.32 -0.002 270)
			(size 0.46 0.4)
			(layers "F.Cu" "F.Mask")
			(roundrect_rratio 0.25)
			(net 1 "GND")
			(pintype "passive")
		)
	)
	(footprint "antmicro-footprints:C_0201"
		(layer "F.Cu")
		(at 157.425 83.35 90)
		(descr "Capacitor SMD 0201")
		(tags "capacitor SMD 0201")
		(property "Reference" "C25"
			(at 0.59999 0.412957 90)
			(layer "F.SilkS")
			(effects
				(font
					(size 0.7 0.7)
					(thickness 0.15)
				)
				(justify left bottom)
			)
		)
		(property "Value" "C_100n_0201"
			(at 0 1.4 90)
			(layer "F.Fab")
			(hide yes)
			(effects
				(font
					(size 0.7 0.7)
					(thickness 0.15)
				)
				(justify left bottom)
			)
		)
		(property "Description" "SMD Multilayer Ceramic Capacitor, 0.1 µF, 6.3 V, 0201 [0603 Metric], ± 10%, X6S, CC Series"
			(at 0 0 90)
			(layer "F.Fab")
			(hide yes)
			(effects
				(font
					(size 1.27 1.27)
					(thickness 0.15)
				)
			)
		)
		(property "Author" "Antmicro"
			(at 240.775 -74.075 0)
			(layer "F.Fab")
			(hide yes)
			(effects
				(font
					(size 1 1)
					(thickness 0.15)
				)
			)
		)
		(property "Dielectric" ""
			(at 240.775 -74.075 0)
			(layer "F.Fab")
			(hide yes)
			(effects
				(font
					(size 1 1)
					(thickness 0.15)
				)
			)
		)
		(property "License" "Apache-2.0"
			(at 240.775 -74.075 0)
			(layer "F.Fab")
			(hide yes)
			(effects
				(font
					(size 1 1)
					(thickness 0.15)
				)
			)
		)
		(property "MPN" "CC0201KRX6S5BB104"
			(at 240.775 -74.075 0)
			(layer "F.Fab")
			(hide yes)
			(effects
				(font
					(size 1 1)
					(thickness 0.15)
				)
			)
		)
		(property "Manufacturer" "YAGEO"
			(at 240.775 -74.075 0)
			(layer "F.Fab")
			(hide yes)
			(effects
				(font
					(size 1 1)
					(thickness 0.15)
				)
			)
		)
		(property "Public" "False"
			(at 240.775 -74.075 0)
			(layer "F.Fab")
			(hide yes)
			(effects
				(font
					(size 1 1)
					(thickness 0.15)
				)
			)
		)
		(property "Val" "100n"
			(at 240.775 -74.075 0)
			(layer "F.Fab")
			(hide yes)
			(effects
				(font
					(size 1 1)
					(thickness 0.15)
				)
			)
		)
		(property "Voltage" ""
			(at 240.775 -74.075 0)
			(layer "F.Fab")
			(hide yes)
			(effects
				(font
					(size 1 1)
					(thickness 0.15)
				)
			)
		)
		(sheetname "DDR5")
		(sheetfile "ddr5.kicad_sch")
		(attr smd)
		(fp_rect
			(start -0.7 -0.35)
			(end 0.7 0.35)
			(stroke
				(width 0.05)
				(type default)
			)
			(fill no)
			(layer "F.CrtYd")
		)
		(fp_rect
			(start 0.3 0.15)
			(end -0.301 -0.149)
			(stroke
				(width 0.15)
				(type solid)
			)
			(fill no)
			(layer "F.Fab")
		)
		(pad "" smd roundrect
			(at -0.349 -0.002 90)
			(size 0.318 0.36)
			(layers "F.Paste")
			(roundrect_rratio 0.25)
		)
		(pad "" smd roundrect
			(at 0.341 -0.002 90)
			(size 0.318 0.36)
			(layers "F.Paste")
			(roundrect_rratio 0.25)
		)
		(pad "1" smd roundrect
			(at -0.321 -0.002 90)
			(size 0.46 0.4)
			(layers "F.Cu" "F.Mask")
			(roundrect_rratio 0.25)
			(net 19 "VPP")
			(pintype "passive")
		)
		(pad "2" smd roundrect
			(at 0.32 -0.002 90)
			(size 0.46 0.4)
			(layers "F.Cu" "F.Mask")
			(roundrect_rratio 0.25)
			(net 1 "GND")
			(pintype "passive")
		)
	)
	(footprint "antmicro-footprints:R_0402_1005Metric"
		(layer "F.Cu")
		(at 158.325 83.575 -90)
		(descr "Resistor SMD 0402")
		(tags "resistor SMD 0402")
		(property "Reference" "R18"
			(at -0.815 -0.425 270)
			(layer "F.SilkS")
			(effects
				(font
					(size 0.7 0.7)
					(thickness 0.15)
				)
				(justify left bottom)
			)
		)
		(property "Value" "R_0R_0402"
			(at 0 1.4 270)
			(layer "F.Fab")
			(hide yes)
			(effects
				(font
					(size 0.7 0.7)
					(thickness 0.15)
				)
				(justify left bottom)
			)
		)
		(property "Description" "0R resistor in 0402 package with unspecified tolerance"
			(at 0 0 270)
			(layer "F.Fab")
			(hide yes)
			(effects
				(font
					(size 1.27 1.27)
					(thickness 0.15)
				)
			)
		)
		(property "Author" "Antmicro"
			(at 74.75 241.9 0)
			(layer "F.Fab")
			(hide yes)
			(effects
				(font
					(size 1 1)
					(thickness 0.15)
				)
			)
		)
		(property "Current" "1A"
			(at 74.75 241.9 0)
			(layer "F.Fab")
			(hide yes)
			(effects
				(font
					(size 1 1)
					(thickness 0.15)
				)
			)
		)
		(property "License" "Apache-2.0"
			(at 74.75 241.9 0)
			(layer "F.Fab")
			(hide yes)
			(effects
				(font
					(size 1 1)
					(thickness 0.15)
				)
			)
		)
		(property "MPN" "ERJ2GE0R00X"
			(at 74.75 241.9 0)
			(layer "F.Fab")
			(hide yes)
			(effects
				(font
					(size 1 1)
					(thickness 0.15)
				)
			)
		)
		(property "Manufacturer" "Panasonic"
			(at 74.75 241.9 0)
			(layer "F.Fab")
			(hide yes)
			(effects
				(font
					(size 1 1)
					(thickness 0.15)
				)
			)
		)
		(property "Tolerance" ""
			(at 74.75 241.9 0)
			(layer "F.Fab")
			(hide yes)
			(effects
				(font
					(size 1 1)
					(thickness 0.15)
				)
			)
		)
		(property "Val" "0R"
			(at 74.75 241.9 0)
			(layer "F.Fab")
			(hide yes)
			(effects
				(font
					(size 1 1)
					(thickness 0.15)
				)
			)
		)
		(sheetname "DDR5")
		(sheetfile "ddr5.kicad_sch")
		(attr smd)
		(fp_rect
			(start -0.925 -0.47)
			(end 0.925 0.47)
			(stroke
				(width 0.05)
				(type default)
			)
			(fill no)
			(layer "F.CrtYd")
		)
		(fp_rect
			(start -0.5 -0.25)
			(end 0.5 0.25)
			(stroke
				(width 0.15)
				(type solid)
			)
			(fill no)
			(layer "F.Fab")
		)
		(pad "1" smd roundrect
			(at -0.48 0 270)
			(size 0.59 0.64)
			(layers "F.Cu" "F.Mask" "F.Paste")
			(roundrect_rratio 0.25)
			(net 65 "/DDR5/R_LBDQ")
			(pintype "passive")
		)
		(pad "2" smd roundrect
			(at 0.48 0 270)
			(size 0.59 0.64)
			(layers "F.Cu" "F.Mask" "F.Paste")
			(roundrect_rratio 0.25)
			(net 38 "LBDQ")
			(pintype "passive")
		)
	)
)
